# SCM (Grand Teton) — schematic netlist excerpt (pin names and nets, part order shuffled) for the footprints in the layout excerpt that follows; sources: Cadence DE-HDL packaged netlist, KiCad conversion of 12092022_DA0F0TMDCD0_F0T_Management_Board_D_brd_V3_OCP.brd

R354  Q_RES  120 1% CHIP  pkg 0402LF  page 20 : A = M_BMC_DDR4_MA<3> ; B = P1V2_AUX
C48  Q_CAP  1UF 25V 10% X6S  pkg C0402  page 17 : A = P3V3_STBY_DACAV33 ; B = GND

(kicad_pcb
	(version 20260206)
	(generator "pcbnew")
	(generator_version "10.0")
	(general
		(thickness 1.6)
		(legacy_teardrops no)
	)
	(paper "A4")
	(title_block
		(title "12092022_DA0F0TMDCD0_F0T_Management_Board_D_brd_V3_OCP.brd")
		(comment 1 "Grand Teton / footprints 787-788 of 1440")
	)
	(layers
		(0 "F.Cu" signal "TOP")
		(4 "In1.Cu" signal "GND")
		(6 "In2.Cu" signal "IN1")
		(8 "In3.Cu" signal "GND1")
		(10 "In4.Cu" signal "IN2")
		(12 "In5.Cu" signal "VCC")
		(14 "In6.Cu" signal "VCC1")
		(16 "In7.Cu" signal "IN3")
		(18 "In8.Cu" signal "GND2")
		(20 "In9.Cu" signal "IN4")
		(22 "In10.Cu" signal "GND3")
		(2 "B.Cu" signal "BOTTOM")
		(9 "F.Adhes" user "F.Adhesive")
		(11 "B.Adhes" user "B.Adhesive")
		(13 "F.Paste" user "Package Geometry/Pastemask Top")
		(15 "B.Paste" user "Package Geometry/Pastemask Bottom")
		(5 "F.SilkS" user "Ref Des/Silkscreen Top")
		(7 "B.SilkS" user "Ref Des/Silkscreen Bottom")
		(1 "F.Mask" user "Board Geometry/Soldermask Top")
		(3 "B.Mask" user "Board Geometry/Soldermask Bottom")
		(17 "Dwgs.User" user "User.Drawings")
		(19 "Cmts.User" user "User.Comments")
		(21 "Eco1.User" user "User.Eco1")
		(23 "Eco2.User" user "User.Eco2")
		(25 "Edge.Cuts" user "Board Geometry/Outline")
		(27 "Margin" user)
		(31 "F.CrtYd" user "Package Geometry/Place Bound Top")
		(29 "B.CrtYd" user "Package Geometry/Place Bound Bottom")
		(35 "F.Fab" user "Ref Des/Assembly Top")
		(33 "B.Fab" user "Ref Des/Assembly Bottom")
	)
	(footprint ""
		(layer "B.Cu")
		(at 83.16722 -42.522394 180)
		(property "Reference" "R354"
			(at 0 0 0)
			(layer "B.SilkS")
			(hide yes)
			(effects
				(font
					(size 1.27 1.27)
				)
				(justify mirror)
			)
		)
		(property "Value" ""
			(at 0 0 0)
			(layer "B.Fab")
			(effects
				(font
					(size 1.27 1.27)
				)
				(justify mirror)
			)
		)
		(duplicate_pad_numbers_are_jumpers no)
		(fp_line
			(start 0.7874 0.4064)
			(end 0.7874 -0.4064)
			(stroke
				(width 0.1524)
				(type default)
			)
			(layer "B.SilkS")
		)
		(fp_line
			(start 0.7874 -0.4064)
			(end -0.7874 -0.4064)
			(stroke
				(width 0.1524)
				(type default)
			)
			(layer "B.SilkS")
		)
		(fp_line
			(start -0.7874 0.4064)
			(end 0.7874 0.4064)
			(stroke
				(width 0.1524)
				(type default)
			)
			(layer "B.SilkS")
		)
		(fp_line
			(start -0.7874 -0.4064)
			(end -0.7874 0.4064)
			(stroke
				(width 0.1524)
				(type default)
			)
			(layer "B.SilkS")
		)
		(fp_line
			(start 0.67945 0.3048)
			(end 0.67945 -0.305054)
			(stroke
				(width 0.1)
				(type default)
			)
			(layer "B.Fab")
		)
		(fp_line
			(start 0.67945 -0.305054)
			(end 0.12065 -0.305054)
			(stroke
				(width 0.1)
				(type default)
			)
			(layer "B.Fab")
		)
		(fp_line
			(start 0.12065 0.3048)
			(end 0.67945 0.3048)
			(stroke
				(width 0.1)
				(type default)
			)
			(layer "B.Fab")
		)
		(fp_line
			(start 0.12065 0.2794)
			(end 0.12065 0.3048)
			(stroke
				(width 0.1)
				(type default)
			)
			(layer "B.Fab")
		)
		(fp_line
			(start 0.12065 -0.2794)
			(end -0.12065 -0.2794)
			(stroke
				(width 0.1)
				(type default)
			)
			(layer "B.Fab")
		)
		(fp_line
			(start 0.12065 -0.305054)
			(end 0.12065 -0.2794)
			(stroke
				(width 0.1)
				(type default)
			)
			(layer "B.Fab")
		)
		(fp_line
			(start -0.120396 0.3048)
			(end -0.120396 0.2794)
			(stroke
				(width 0.1)
				(type default)
			)
			(layer "B.Fab")
		)
		(fp_line
			(start -0.120396 0.2794)
			(end 0.12065 0.2794)
			(stroke
				(width 0.1)
				(type default)
			)
			(layer "B.Fab")
		)
		(fp_line
			(start -0.12065 -0.2794)
			(end -0.12065 -0.3048)
			(stroke
				(width 0.1)
				(type default)
			)
			(layer "B.Fab")
		)
		(fp_line
			(start -0.12065 -0.3048)
			(end -0.67945 -0.3048)
			(stroke
				(width 0.1)
				(type default)
			)
			(layer "B.Fab")
		)
		(fp_line
			(start -0.67945 0.3048)
			(end -0.120396 0.3048)
			(stroke
				(width 0.1)
				(type default)
			)
			(layer "B.Fab")
		)
		(fp_line
			(start -0.67945 -0.3048)
			(end -0.67945 0.3048)
			(stroke
				(width 0.1)
				(type default)
			)
			(layer "B.Fab")
		)
		(pad "1" smd circle
			(at 0.40005 0)
			(size 0 0)
			(layers "B.Cu" "B.Mask" "B.Paste")
			(net "M_BMC_DDR4_MA<3>")
		)
		(pad "2" smd circle
			(at -0.40005 0)
			(size 0 0)
			(layers "B.Cu" "B.Mask" "B.Paste")
			(net "P1V2_AUX")
		)
	)
	(footprint ""
		(layer "B.Cu")
		(at 43.28922 -53.856382)
		(property "Reference" "C48"
			(at 0 0 0)
			(layer "B.SilkS")
			(hide yes)
			(effects
				(font
					(size 1.27 1.27)
				)
				(justify mirror)
			)
		)
		(property "Value" ""
			(at 0 0 0)
			(layer "B.Fab")
			(effects
				(font
					(size 1.27 1.27)
				)
				(justify mirror)
			)
		)
		(duplicate_pad_numbers_are_jumpers no)
		(fp_line
			(start -0.7874 -0.4064)
			(end -0.7874 0.4064)
			(stroke
				(width 0.1524)
				(type default)
			)
			(layer "B.SilkS")
		)
		(fp_line
			(start -0.7874 0.4064)
			(end 0.7874 0.4064)
			(stroke
				(width 0.1524)
				(type default)
			)
			(layer "B.SilkS")
		)
		(fp_line
			(start 0.7874 -0.4064)
			(end -0.7874 -0.4064)
			(stroke
				(width 0.1524)
				(type default)
			)
			(layer "B.SilkS")
		)
		(fp_line
			(start 0.7874 0.4064)
			(end 0.7874 -0.4064)
			(stroke
				(width 0.1524)
				(type default)
			)
			(layer "B.SilkS")
		)
		(fp_line
			(start -0.67945 -0.3048)
			(end -0.67945 0.3048)
			(stroke
				(width 0.1)
				(type default)
			)
			(layer "B.Fab")
		)
		(fp_line
			(start -0.67945 0.3048)
			(end -0.120396 0.3048)
			(stroke
				(width 0.1)
				(type default)
			)
			(layer "B.Fab")
		)
		(fp_line
			(start -0.12065 -0.3048)
			(end -0.67945 -0.3048)
			(stroke
				(width 0.1)
				(type default)
			)
			(layer "B.Fab")
		)
		(fp_line
			(start -0.12065 -0.2794)
			(end -0.12065 -0.3048)
			(stroke
				(width 0.1)
				(type default)
			)
			(layer "B.Fab")
		)
		(fp_line
			(start -0.120396 0.2794)
			(end 0.12065 0.2794)
			(stroke
				(width 0.1)
				(type default)
			)
			(layer "B.Fab")
		)
		(fp_line
			(start -0.120396 0.3048)
			(end -0.120396 0.2794)
			(stroke
				(width 0.1)
				(type default)
			)
			(layer "B.Fab")
		)
		(fp_line
			(start 0.12065 -0.305054)
			(end 0.12065 -0.2794)
			(stroke
				(width 0.1)
				(type default)
			)
			(layer "B.Fab")
		)
		(fp_line
			(start 0.12065 -0.2794)
			(end -0.12065 -0.2794)
			(stroke
				(width 0.1)
				(type default)
			)
			(layer "B.Fab")
		)
		(fp_line
			(start 0.12065 0.2794)
			(end 0.12065 0.3048)
			(stroke
				(width 0.1)
				(type default)
			)
			(layer "B.Fab")
		)
		(fp_line
			(start 0.12065 0.3048)
			(end 0.67945 0.3048)
			(stroke
				(width 0.1)
				(type default)
			)
			(layer "B.Fab")
		)
		(fp_line
			(start 0.67945 -0.305054)
			(end 0.12065 -0.305054)
			(stroke
				(width 0.1)
				(type default)
			)
			(layer "B.Fab")
		)
		(fp_line
			(start 0.67945 0.3048)
			(end 0.67945 -0.305054)
			(stroke
				(width 0.1)
				(type default)
			)
			(layer "B.Fab")
		)
		(pad "1" smd circle
			(at 0.40005 0 180)
			(size 0 0)
			(layers "B.Cu" "B.Mask" "B.Paste")
			(net "P3V3_STBY_DACAV33")
		)
		(pad "2" smd circle
			(at -0.40005 0 180)
			(size 0 0)
			(layers "B.Cu" "B.Mask" "B.Paste")
			(net "GND")
		)
	)
)
